#ISCELL
  mstr_misc dns *
  *
#ISCELL
  mstr_symbols design_note *
  *
#ISCELL
  mstr_symbols intel_corp_bpage *
  *
#CELL
  mstr_discrete res *
  page126_i10
#ISCELL
  mstr_standard offpage *
  page126_i11
#CELL
  mstr_discrete res *
  page126_i12
#CELL
  mstr_discrete fet_n *
  page126_i13
#ISCELL
  mstr_symbols gnd *
  page126_i14
#ISCELL
  mstr_symbols p3v3_stby *
  page126_i16
#ISCELL
  mstr_standard offpage *
  page126_i17
#CELL
  mstr_discrete res *
  page126_i20
#ISCELL
  mstr_standard offpage *
  page126_i21
#CELL
  mstr_discrete res *
  page126_i22
#CELL
  mstr_discrete res *
  page126_i23
#ISCELL
  mstr_symbols gnd *
  page126_i24
#ISCELL
  mstr_symbols p3v3_stby *
  page126_i25
#ISCELL
  mstr_standard offpage *
  page126_i26
#ISCELL
  mstr_symbols gnd *
  page126_i5
#CELL
  mstr_discrete res *
  page126_i6
#ISCELL
  mstr_symbols p3v3_stby *
  page126_i7
#ISCELL
  mstr_standard offpage *
  page126_i8
#ISCELL
  mstr_symbols p3v3_stby *
  page126_i9
